(kicad_pcb
	(version 20260206)
	(generator "pcbnew")
	(generator_version "10.0")
	(general
		(thickness 1.6)
		(legacy_teardrops no)
	)
	(paper "A4")
	(title_block
		(title "01162023_DA0F0TEBIF0_F0T_Expander_BD_F_brd_V02_OCP.brd")
		(comment 1 "Grand Teton / footprints 9153-9160 of 9728")
	)
	(layers
		(0 "F.Cu" signal "TOP")
		(4 "In1.Cu" signal "GND")
		(6 "In2.Cu" signal "VCC")
		(8 "In3.Cu" signal "VCC1")
		(10 "In4.Cu" signal "GND1")
		(12 "In5.Cu" signal "IN1")
		(14 "In6.Cu" signal "GND2")
		(16 "In7.Cu" signal "IN2")
		(18 "In8.Cu" signal "GND3")
		(20 "In9.Cu" signal "IN3")
		(22 "In10.Cu" signal "GND4")
		(24 "In11.Cu" signal "IN4")
		(26 "In12.Cu" signal "GND5")
		(28 "In13.Cu" signal "IN5")
		(30 "In14.Cu" signal "GND6")
		(32 "In15.Cu" signal "IN6")
		(34 "In16.Cu" signal "GND7")
		(2 "B.Cu" signal "BOTTOM")
		(9 "F.Adhes" user "F.Adhesive")
		(11 "B.Adhes" user "B.Adhesive")
		(13 "F.Paste" user "Package Geometry/Pastemask Top")
		(15 "B.Paste" user "Package Geometry/Pastemask Bottom")
		(5 "F.SilkS" user "Ref Des/Silkscreen Top")
		(7 "B.SilkS" user "Ref Des/Silkscreen Bottom")
		(1 "F.Mask" user "Board Geometry/Soldermask Top")
		(3 "B.Mask" user "Board Geometry/Soldermask Bottom")
		(17 "Dwgs.User" user "User.Drawings")
		(19 "Cmts.User" user "User.Comments")
		(21 "Eco1.User" user "User.Eco1")
		(23 "Eco2.User" user "User.Eco2")
		(25 "Edge.Cuts" user "Board Geometry/Outline")
		(27 "Margin" user)
		(31 "F.CrtYd" user "Package Geometry/Place Bound Top")
		(29 "B.CrtYd" user "Package Geometry/Place Bound Bottom")
		(35 "F.Fab" user "Ref Des/Assembly Top")
		(33 "B.Fab" user "Ref Des/Assembly Bottom")
	)
	(footprint ""
		(layer "B.Cu")
		(at 422.326816 -299.2247 90)
		(property "Reference" "R1448"
			(at 0 0 90)
			(layer "B.SilkS")
			(hide yes)
			(effects
				(font
					(size 1.27 1.27)
				)
				(justify mirror)
			)
		)
		(property "Value" ""
			(at 0 0 90)
			(layer "B.Fab")
			(effects
				(font
					(size 1.27 1.27)
				)
				(justify mirror)
			)
		)
		(duplicate_pad_numbers_are_jumpers no)
		(fp_line
			(start 0.7874 -0.4064)
			(end -0.7874 -0.4064)
			(stroke
				(width 0.1524)
				(type default)
			)
			(layer "B.SilkS")
		)
		(fp_line
			(start -0.7874 -0.4064)
			(end -0.7874 0.4064)
			(stroke
				(width 0.1524)
				(type default)
			)
			(layer "B.SilkS")
		)
		(fp_line
			(start 0.7874 0.4064)
			(end 0.7874 -0.4064)
			(stroke
				(width 0.1524)
				(type default)
			)
			(layer "B.SilkS")
		)
		(fp_line
			(start -0.7874 0.4064)
			(end 0.7874 0.4064)
			(stroke
				(width 0.1524)
				(type default)
			)
			(layer "B.SilkS")
		)
		(fp_line
			(start 0.67945 -0.305054)
			(end 0.12065 -0.305054)
			(stroke
				(width 0.1)
				(type default)
			)
			(layer "B.Fab")
		)
		(fp_line
			(start 0.12065 -0.305054)
			(end 0.12065 -0.2794)
			(stroke
				(width 0.1)
				(type default)
			)
			(layer "B.Fab")
		)
		(fp_line
			(start -0.12065 -0.3048)
			(end -0.67945 -0.3048)
			(stroke
				(width 0.1)
				(type default)
			)
			(layer "B.Fab")
		)
		(fp_line
			(start -0.67945 -0.3048)
			(end -0.67945 0.3048)
			(stroke
				(width 0.1)
				(type default)
			)
			(layer "B.Fab")
		)
		(fp_line
			(start 0.12065 -0.2794)
			(end -0.12065 -0.2794)
			(stroke
				(width 0.1)
				(type default)
			)
			(layer "B.Fab")
		)
		(fp_line
			(start -0.12065 -0.2794)
			(end -0.12065 -0.3048)
			(stroke
				(width 0.1)
				(type default)
			)
			(layer "B.Fab")
		)
		(fp_line
			(start 0.12065 0.2794)
			(end 0.12065 0.3048)
			(stroke
				(width 0.1)
				(type default)
			)
			(layer "B.Fab")
		)
		(fp_line
			(start -0.120396 0.2794)
			(end 0.12065 0.2794)
			(stroke
				(width 0.1)
				(type default)
			)
			(layer "B.Fab")
		)
		(fp_line
			(start 0.67945 0.3048)
			(end 0.67945 -0.305054)
			(stroke
				(width 0.1)
				(type default)
			)
			(layer "B.Fab")
		)
		(fp_line
			(start 0.12065 0.3048)
			(end 0.67945 0.3048)
			(stroke
				(width 0.1)
				(type default)
			)
			(layer "B.Fab")
		)
		(fp_line
			(start -0.120396 0.3048)
			(end -0.120396 0.2794)
			(stroke
				(width 0.1)
				(type default)
			)
			(layer "B.Fab")
		)
		(fp_line
			(start -0.67945 0.3048)
			(end -0.120396 0.3048)
			(stroke
				(width 0.1)
				(type default)
			)
			(layer "B.Fab")
		)
		(pad "1" smd circle
			(at 0.40005 0 270)
			(size 0 0)
			(layers "B.Cu" "B.Mask" "B.Paste")
			(net "PEX3_ADCTEMP_VINP1")
		)
		(pad "2" smd circle
			(at -0.40005 0 270)
			(size 0 0)
			(layers "B.Cu" "B.Mask" "B.Paste")
			(net "GND")
		)
	)
	(footprint ""
		(layer "B.Cu")
		(at 303.249838 -293.52494 180)
		(property "Reference" "C3288"
			(at 0 0 0)
			(layer "B.SilkS")
			(hide yes)
			(effects
				(font
					(size 1.27 1.27)
				)
				(justify mirror)
			)
		)
		(property "Value" ""
			(at 0 0 0)
			(layer "B.Fab")
			(effects
				(font
					(size 1.27 1.27)
				)
				(justify mirror)
			)
		)
		(duplicate_pad_numbers_are_jumpers no)
		(fp_line
			(start 0.299974 0.150114)
			(end 0.299974 -0.150114)
			(stroke
				(width 0.1)
				(type default)
			)
			(layer "B.Fab")
		)
		(fp_line
			(start 0.299974 -0.150114)
			(end -0.299974 -0.150114)
			(stroke
				(width 0.1)
				(type default)
			)
			(layer "B.Fab")
		)
		(fp_line
			(start -0.299974 0.150114)
			(end 0.299974 0.150114)
			(stroke
				(width 0.1)
				(type default)
			)
			(layer "B.Fab")
		)
		(fp_line
			(start -0.299974 -0.150114)
			(end -0.299974 0.150114)
			(stroke
				(width 0.1)
				(type default)
			)
			(layer "B.Fab")
		)
		(pad "1" smd rect
			(at 0.2667 0)
			(size 0.3048 0.381)
			(layers "B.Cu" "B.Mask" "B.Paste")
			(net "P1V25_PEX2")
		)
		(pad "2" smd rect
			(at -0.2667 0)
			(size 0.3048 0.381)
			(layers "B.Cu" "B.Mask" "B.Paste")
			(net "GND")
		)
	)
	(footprint ""
		(layer "B.Cu")
		(at 337.967828 -323.15531 -90)
		(property "Reference" "R6518"
			(at 0 0 90)
			(layer "B.SilkS")
			(hide yes)
			(effects
				(font
					(size 1.27 1.27)
				)
				(justify mirror)
			)
		)
		(property "Value" ""
			(at 0 0 90)
			(layer "B.Fab")
			(effects
				(font
					(size 1.27 1.27)
				)
				(justify mirror)
			)
		)
		(duplicate_pad_numbers_are_jumpers no)
		(fp_line
			(start -0.7874 0.4064)
			(end 0.7874 0.4064)
			(stroke
				(width 0.1524)
				(type default)
			)
			(layer "B.SilkS")
		)
		(fp_line
			(start 0.7874 0.4064)
			(end 0.7874 -0.4064)
			(stroke
				(width 0.1524)
				(type default)
			)
			(layer "B.SilkS")
		)
		(fp_line
			(start -0.7874 -0.4064)
			(end -0.7874 0.4064)
			(stroke
				(width 0.1524)
				(type default)
			)
			(layer "B.SilkS")
		)
		(fp_line
			(start 0.7874 -0.4064)
			(end -0.7874 -0.4064)
			(stroke
				(width 0.1524)
				(type default)
			)
			(layer "B.SilkS")
		)
		(fp_line
			(start -0.67945 0.3048)
			(end -0.120396 0.3048)
			(stroke
				(width 0.1)
				(type default)
			)
			(layer "B.Fab")
		)
		(fp_line
			(start -0.120396 0.3048)
			(end -0.120396 0.2794)
			(stroke
				(width 0.1)
				(type default)
			)
			(layer "B.Fab")
		)
		(fp_line
			(start 0.12065 0.3048)
			(end 0.67945 0.3048)
			(stroke
				(width 0.1)
				(type default)
			)
			(layer "B.Fab")
		)
		(fp_line
			(start 0.67945 0.3048)
			(end 0.67945 -0.305054)
			(stroke
				(width 0.1)
				(type default)
			)
			(layer "B.Fab")
		)
		(fp_line
			(start -0.120396 0.2794)
			(end 0.12065 0.2794)
			(stroke
				(width 0.1)
				(type default)
			)
			(layer "B.Fab")
		)
		(fp_line
			(start 0.12065 0.2794)
			(end 0.12065 0.3048)
			(stroke
				(width 0.1)
				(type default)
			)
			(layer "B.Fab")
		)
		(fp_line
			(start -0.12065 -0.2794)
			(end -0.12065 -0.3048)
			(stroke
				(width 0.1)
				(type default)
			)
			(layer "B.Fab")
		)
		(fp_line
			(start 0.12065 -0.2794)
			(end -0.12065 -0.2794)
			(stroke
				(width 0.1)
				(type default)
			)
			(layer "B.Fab")
		)
		(fp_line
			(start -0.67945 -0.3048)
			(end -0.67945 0.3048)
			(stroke
				(width 0.1)
				(type default)
			)
			(layer "B.Fab")
		)
		(fp_line
			(start -0.12065 -0.3048)
			(end -0.67945 -0.3048)
			(stroke
				(width 0.1)
				(type default)
			)
			(layer "B.Fab")
		)
		(fp_line
			(start 0.12065 -0.305054)
			(end 0.12065 -0.2794)
			(stroke
				(width 0.1)
				(type default)
			)
			(layer "B.Fab")
		)
		(fp_line
			(start 0.67945 -0.305054)
			(end 0.12065 -0.305054)
			(stroke
				(width 0.1)
				(type default)
			)
			(layer "B.Fab")
		)
		(pad "1" smd circle
			(at 0.40005 0 90)
			(size 0 0)
			(layers "B.Cu" "B.Mask" "B.Paste")
			(net "P0V8_SERDES_VDDA_PEX2")
		)
		(pad "2" smd circle
			(at -0.40005 0 90)
			(size 0 0)
			(layers "B.Cu" "B.Mask" "B.Paste")
			(net "P0V8_SERDES_VDDA_PEX2_C11")
		)
	)
	(footprint ""
		(layer "B.Cu")
		(at 278.554942 -299.212)
		(property "Reference" "C3374"
			(at 0 0 0)
			(layer "B.SilkS")
			(hide yes)
			(effects
				(font
					(size 1.27 1.27)
				)
				(justify mirror)
			)
		)
		(property "Value" ""
			(at 0 0 0)
			(layer "B.Fab")
			(effects
				(font
					(size 1.27 1.27)
				)
				(justify mirror)
			)
		)
		(duplicate_pad_numbers_are_jumpers no)
		(fp_line
			(start -0.299974 -0.150114)
			(end -0.299974 0.150114)
			(stroke
				(width 0.1)
				(type default)
			)
			(layer "B.Fab")
		)
		(fp_line
			(start -0.299974 0.150114)
			(end 0.299974 0.150114)
			(stroke
				(width 0.1)
				(type default)
			)
			(layer "B.Fab")
		)
		(fp_line
			(start 0.299974 -0.150114)
			(end -0.299974 -0.150114)
			(stroke
				(width 0.1)
				(type default)
			)
			(layer "B.Fab")
		)
		(fp_line
			(start 0.299974 0.150114)
			(end 0.299974 -0.150114)
			(stroke
				(width 0.1)
				(type default)
			)
			(layer "B.Fab")
		)
		(pad "1" smd rect
			(at 0.2667 0 180)
			(size 0.3048 0.381)
			(layers "B.Cu" "B.Mask" "B.Paste")
			(net "PCEPLL1_VDDA18_PEX2")
		)
		(pad "2" smd rect
			(at -0.2667 0 180)
			(size 0.3048 0.381)
			(layers "B.Cu" "B.Mask" "B.Paste")
			(net "GND")
		)
	)
	(footprint ""
		(layer "B.Cu")
		(at 347.025214 -282.244292 180)
		(property "Reference" "PR7172"
			(at 0 0 0)
			(layer "B.SilkS")
			(hide yes)
			(effects
				(font
					(size 1.27 1.27)
				)
				(justify mirror)
			)
		)
		(property "Value" ""
			(at 0 0 0)
			(layer "B.Fab")
			(effects
				(font
					(size 1.27 1.27)
				)
				(justify mirror)
			)
		)
		(duplicate_pad_numbers_are_jumpers no)
		(fp_line
			(start 0.7874 0.4064)
			(end 0.7874 -0.4064)
			(stroke
				(width 0.1524)
				(type default)
			)
			(layer "B.SilkS")
		)
		(fp_line
			(start 0.7874 -0.4064)
			(end -0.7874 -0.4064)
			(stroke
				(width 0.1524)
				(type default)
			)
			(layer "B.SilkS")
		)
		(fp_line
			(start -0.7874 0.4064)
			(end 0.7874 0.4064)
			(stroke
				(width 0.1524)
				(type default)
			)
			(layer "B.SilkS")
		)
		(fp_line
			(start -0.7874 -0.4064)
			(end -0.7874 0.4064)
			(stroke
				(width 0.1524)
				(type default)
			)
			(layer "B.SilkS")
		)
		(fp_line
			(start 0.67945 0.3048)
			(end 0.67945 -0.305054)
			(stroke
				(width 0.1)
				(type default)
			)
			(layer "B.Fab")
		)
		(fp_line
			(start 0.67945 -0.305054)
			(end 0.12065 -0.305054)
			(stroke
				(width 0.1)
				(type default)
			)
			(layer "B.Fab")
		)
		(fp_line
			(start 0.12065 0.3048)
			(end 0.67945 0.3048)
			(stroke
				(width 0.1)
				(type default)
			)
			(layer "B.Fab")
		)
		(fp_line
			(start 0.12065 0.2794)
			(end 0.12065 0.3048)
			(stroke
				(width 0.1)
				(type default)
			)
			(layer "B.Fab")
		)
		(fp_line
			(start 0.12065 -0.2794)
			(end -0.12065 -0.2794)
			(stroke
				(width 0.1)
				(type default)
			)
			(layer "B.Fab")
		)
		(fp_line
			(start 0.12065 -0.305054)
			(end 0.12065 -0.2794)
			(stroke
				(width 0.1)
				(type default)
			)
			(layer "B.Fab")
		)
		(fp_line
			(start -0.120396 0.3048)
			(end -0.120396 0.2794)
			(stroke
				(width 0.1)
				(type default)
			)
			(layer "B.Fab")
		)
		(fp_line
			(start -0.120396 0.2794)
			(end 0.12065 0.2794)
			(stroke
				(width 0.1)
				(type default)
			)
			(layer "B.Fab")
		)
		(fp_line
			(start -0.12065 -0.2794)
			(end -0.12065 -0.3048)
			(stroke
				(width 0.1)
				(type default)
			)
			(layer "B.Fab")
		)
		(fp_line
			(start -0.12065 -0.3048)
			(end -0.67945 -0.3048)
			(stroke
				(width 0.1)
				(type default)
			)
			(layer "B.Fab")
		)
		(fp_line
			(start -0.67945 0.3048)
			(end -0.120396 0.3048)
			(stroke
				(width 0.1)
				(type default)
			)
			(layer "B.Fab")
		)
		(fp_line
			(start -0.67945 -0.3048)
			(end -0.67945 0.3048)
			(stroke
				(width 0.1)
				(type default)
			)
			(layer "B.Fab")
		)
		(pad "1" smd circle
			(at 0.40005 0)
			(size 0 0)
			(layers "B.Cu" "B.Mask" "B.Paste")
			(net "P0V8_PEX2_EN2")
		)
		(pad "2" smd circle
			(at -0.40005 0)
			(size 0 0)
			(layers "B.Cu" "B.Mask" "B.Paste")
			(net "P0V8_PEX2_VCC2")
		)
	)
	(footprint ""
		(layer "B.Cu")
		(at 106.70032 -282.251404 180)
		(property "Reference" "PR7167"
			(at 0 0 0)
			(layer "B.SilkS")
			(hide yes)
			(effects
				(font
					(size 1.27 1.27)
				)
				(justify mirror)
			)
		)
		(property "Value" ""
			(at 0 0 0)
			(layer "B.Fab")
			(effects
				(font
					(size 1.27 1.27)
				)
				(justify mirror)
			)
		)
		(duplicate_pad_numbers_are_jumpers no)
		(fp_line
			(start 0.7874 0.4064)
			(end 0.7874 -0.4064)
			(stroke
				(width 0.1524)
				(type default)
			)
			(layer "B.SilkS")
		)
		(fp_line
			(start 0.7874 -0.4064)
			(end -0.7874 -0.4064)
			(stroke
				(width 0.1524)
				(type default)
			)
			(layer "B.SilkS")
		)
		(fp_line
			(start -0.7874 0.4064)
			(end 0.7874 0.4064)
			(stroke
				(width 0.1524)
				(type default)
			)
			(layer "B.SilkS")
		)
		(fp_line
			(start -0.7874 -0.4064)
			(end -0.7874 0.4064)
			(stroke
				(width 0.1524)
				(type default)
			)
			(layer "B.SilkS")
		)
		(fp_line
			(start 0.67945 0.3048)
			(end 0.67945 -0.305054)
			(stroke
				(width 0.1)
				(type default)
			)
			(layer "B.Fab")
		)
		(fp_line
			(start 0.67945 -0.305054)
			(end 0.12065 -0.305054)
			(stroke
				(width 0.1)
				(type default)
			)
			(layer "B.Fab")
		)
		(fp_line
			(start 0.12065 0.3048)
			(end 0.67945 0.3048)
			(stroke
				(width 0.1)
				(type default)
			)
			(layer "B.Fab")
		)
		(fp_line
			(start 0.12065 0.2794)
			(end 0.12065 0.3048)
			(stroke
				(width 0.1)
				(type default)
			)
			(layer "B.Fab")
		)
		(fp_line
			(start 0.12065 -0.2794)
			(end -0.12065 -0.2794)
			(stroke
				(width 0.1)
				(type default)
			)
			(layer "B.Fab")
		)
		(fp_line
			(start 0.12065 -0.305054)
			(end 0.12065 -0.2794)
			(stroke
				(width 0.1)
				(type default)
			)
			(layer "B.Fab")
		)
		(fp_line
			(start -0.120396 0.3048)
			(end -0.120396 0.2794)
			(stroke
				(width 0.1)
				(type default)
			)
			(layer "B.Fab")
		)
		(fp_line
			(start -0.120396 0.2794)
			(end 0.12065 0.2794)
			(stroke
				(width 0.1)
				(type default)
			)
			(layer "B.Fab")
		)
		(fp_line
			(start -0.12065 -0.2794)
			(end -0.12065 -0.3048)
			(stroke
				(width 0.1)
				(type default)
			)
			(layer "B.Fab")
		)
		(fp_line
			(start -0.12065 -0.3048)
			(end -0.67945 -0.3048)
			(stroke
				(width 0.1)
				(type default)
			)
			(layer "B.Fab")
		)
		(fp_line
			(start -0.67945 0.3048)
			(end -0.120396 0.3048)
			(stroke
				(width 0.1)
				(type default)
			)
			(layer "B.Fab")
		)
		(fp_line
			(start -0.67945 -0.3048)
			(end -0.67945 0.3048)
			(stroke
				(width 0.1)
				(type default)
			)
			(layer "B.Fab")
		)
		(pad "1" smd circle
			(at 0.40005 0)
			(size 0 0)
			(layers "B.Cu" "B.Mask" "B.Paste")
			(net "P0V8_PEX0_EN1")
		)
		(pad "2" smd circle
			(at -0.40005 0)
			(size 0 0)
			(layers "B.Cu" "B.Mask" "B.Paste")
			(net "P0V8_PEX0_VCC1")
		)
	)
	(footprint ""
		(layer "B.Cu")
		(at 135.190992 -174.192438 90)
		(property "Reference" "C2658"
			(at 0 0 90)
			(layer "B.SilkS")
			(hide yes)
			(effects
				(font
					(size 1.27 1.27)
				)
				(justify mirror)
			)
		)
		(property "Value" ""
			(at 0 0 90)
			(layer "B.Fab")
			(effects
				(font
					(size 1.27 1.27)
				)
				(justify mirror)
			)
		)
		(duplicate_pad_numbers_are_jumpers no)
		(fp_line
			(start 0.7874 -0.4064)
			(end -0.7874 -0.4064)
			(stroke
				(width 0.1524)
				(type default)
			)
			(layer "B.SilkS")
		)
		(fp_line
			(start -0.7874 -0.4064)
			(end -0.7874 0.4064)
			(stroke
				(width 0.1524)
				(type default)
			)
			(layer "B.SilkS")
		)
		(fp_line
			(start 0.7874 0.4064)
			(end 0.7874 -0.4064)
			(stroke
				(width 0.1524)
				(type default)
			)
			(layer "B.SilkS")
		)
		(fp_line
			(start -0.7874 0.4064)
			(end 0.7874 0.4064)
			(stroke
				(width 0.1524)
				(type default)
			)
			(layer "B.SilkS")
		)
		(fp_line
			(start 0.67945 -0.305054)
			(end 0.12065 -0.305054)
			(stroke
				(width 0.1)
				(type default)
			)
			(layer "B.Fab")
		)
		(fp_line
			(start 0.12065 -0.305054)
			(end 0.12065 -0.2794)
			(stroke
				(width 0.1)
				(type default)
			)
			(layer "B.Fab")
		)
		(fp_line
			(start -0.12065 -0.3048)
			(end -0.67945 -0.3048)
			(stroke
				(width 0.1)
				(type default)
			)
			(layer "B.Fab")
		)
		(fp_line
			(start -0.67945 -0.3048)
			(end -0.67945 0.3048)
			(stroke
				(width 0.1)
				(type default)
			)
			(layer "B.Fab")
		)
		(fp_line
			(start 0.12065 -0.2794)
			(end -0.12065 -0.2794)
			(stroke
				(width 0.1)
				(type default)
			)
			(layer "B.Fab")
		)
		(fp_line
			(start -0.12065 -0.2794)
			(end -0.12065 -0.3048)
			(stroke
				(width 0.1)
				(type default)
			)
			(layer "B.Fab")
		)
		(fp_line
			(start 0.12065 0.2794)
			(end 0.12065 0.3048)
			(stroke
				(width 0.1)
				(type default)
			)
			(layer "B.Fab")
		)
		(fp_line
			(start -0.120396 0.2794)
			(end 0.12065 0.2794)
			(stroke
				(width 0.1)
				(type default)
			)
			(layer "B.Fab")
		)
		(fp_line
			(start 0.67945 0.3048)
			(end 0.67945 -0.305054)
			(stroke
				(width 0.1)
				(type default)
			)
			(layer "B.Fab")
		)
		(fp_line
			(start 0.12065 0.3048)
			(end 0.67945 0.3048)
			(stroke
				(width 0.1)
				(type default)
			)
			(layer "B.Fab")
		)
		(fp_line
			(start -0.120396 0.3048)
			(end -0.120396 0.2794)
			(stroke
				(width 0.1)
				(type default)
			)
			(layer "B.Fab")
		)
		(fp_line
			(start -0.67945 0.3048)
			(end -0.120396 0.3048)
			(stroke
				(width 0.1)
				(type default)
			)
			(layer "B.Fab")
		)
		(pad "1" smd circle
			(at 0.40005 0 270)
			(size 0 0)
			(layers "B.Cu" "B.Mask" "B.Paste")
			(net "P3V3_DB2000QL_VDD")
		)
		(pad "2" smd circle
			(at -0.40005 0 270)
			(size 0 0)
			(layers "B.Cu" "B.Mask" "B.Paste")
			(net "GND")
		)
	)
	(footprint ""
		(layer "B.Cu")
		(at 70.841616 -300.174914)
		(property "Reference" "C2989"
			(at 0 0 0)
			(layer "B.SilkS")
			(hide yes)
			(effects
				(font
					(size 1.27 1.27)
				)
				(justify mirror)
			)
		)
		(property "Value" ""
			(at 0 0 0)
			(layer "B.Fab")
			(effects
				(font
					(size 1.27 1.27)
				)
				(justify mirror)
			)
		)
		(duplicate_pad_numbers_are_jumpers no)
		(fp_line
			(start -0.299974 -0.150114)
			(end -0.299974 0.150114)
			(stroke
				(width 0.1)
				(type default)
			)
			(layer "B.Fab")
		)
		(fp_line
			(start -0.299974 0.150114)
			(end 0.299974 0.150114)
			(stroke
				(width 0.1)
				(type default)
			)
			(layer "B.Fab")
		)
		(fp_line
			(start 0.299974 -0.150114)
			(end -0.299974 -0.150114)
			(stroke
				(width 0.1)
				(type default)
			)
			(layer "B.Fab")
		)
		(fp_line
			(start 0.299974 0.150114)
			(end 0.299974 -0.150114)
			(stroke
				(width 0.1)
				(type default)
			)
			(layer "B.Fab")
		)
		(pad "1" smd rect
			(at 0.2667 0 180)
			(size 0.3048 0.381)
			(layers "B.Cu" "B.Mask" "B.Paste")
			(net "P1V8_VDDA_PEX0")
		)
		(pad "2" smd rect
			(at -0.2667 0 180)
			(size 0.3048 0.381)
			(layers "B.Cu" "B.Mask" "B.Paste")
			(net "GND")
		)
	)
)
